# BASEBOARD_FAB2 (Tioga Pass) — schematic netlist excerpt (pin names and nets, part order shuffled) for the footprints in the layout excerpt that follows; sources: Cadence DE-HDL packaged netlist, KiCad conversion of Wiwynn_Tioga_Pass_MB.brd

C4D29  CAP  220PF 50V 10% X7R  pkg 0402LF  page 201 : A = VSENSE_PVSA_CPU0_BVSP ; B = VSENSE_PVSA_CPU0_N
TH4G1  MTG_KEYHOLE  EMPTY  pkg TH  page 195 : \1\ = GND
C12W3  CAP  47.0PF 50V 5% COG  pkg 0402LF  page 197 : A = VR_PVDDQ_GHJ_AIINSEN ; B = VR_PVDDQ_GHJ_VINSEN

(kicad_pcb
	(version 20260206)
	(generator "pcbnew")
	(generator_version "10.0")
	(general
		(thickness 1.6)
		(legacy_teardrops no)
	)
	(paper "A4")
	(title_block
		(title "Wiwynn_Tioga_Pass_MB.brd")
		(comment 1 "Tioga Pass / footprints 231-233 of 4770")
	)
	(layers
		(0 "F.Cu" signal "TOP")
		(4 "In1.Cu" signal "L2GND")
		(6 "In2.Cu" signal "L3")
		(8 "In3.Cu" signal "L4GND")
		(10 "In4.Cu" signal "L5")
		(12 "In5.Cu" signal "L6GND")
		(14 "In6.Cu" signal "L7VCC")
		(16 "In7.Cu" signal "L8VCC")
		(18 "In8.Cu" signal "L9GND")
		(20 "In9.Cu" signal "L10")
		(22 "In10.Cu" signal "L11GND")
		(24 "In11.Cu" signal "L12")
		(26 "In12.Cu" signal "L13GND")
		(2 "B.Cu" signal "BOTTOM")
		(9 "F.Adhes" user "F.Adhesive")
		(11 "B.Adhes" user "B.Adhesive")
		(13 "F.Paste" user "Package Geometry/Pastemask Top")
		(15 "B.Paste" user "Package Geometry/Pastemask Bottom")
		(5 "F.SilkS" user "Ref Des/Silkscreen Top")
		(7 "B.SilkS" user "Ref Des/Silkscreen Bottom")
		(1 "F.Mask" user "Board Geometry/Soldermask Top")
		(3 "B.Mask" user "Board Geometry/Soldermask Bottom")
		(17 "Dwgs.User" user "User.Drawings")
		(19 "Cmts.User" user "User.Comments")
		(21 "Eco1.User" user "User.Eco1")
		(23 "Eco2.User" user "User.Eco2")
		(25 "Edge.Cuts" user "Board Geometry/Outline")
		(27 "Margin" user)
		(31 "F.CrtYd" user "Package Geometry/Place Bound Top")
		(29 "B.CrtYd" user "Package Geometry/Place Bound Bottom")
		(35 "F.Fab" user "Ref Des/Assembly Top")
		(33 "B.Fab" user "Ref Des/Assembly Bottom")
	)
	(footprint ""
		(layer "F.Cu")
		(at 12.347702 4.098798 -90)
		(property "Reference" "C12W3"
			(at -0.8382 -0.67818 270)
			(unlocked yes)
			(layer "F.SilkS")
			(effects
				(font
					(size 0.4064 0.254)
					(thickness 0.1524)
				)
				(justify left)
			)
		)
		(property "Value" ""
			(at 0 0 270)
			(layer "F.Fab")
			(effects
				(font
					(size 1.27 1.27)
				)
			)
		)
		(duplicate_pad_numbers_are_jumpers no)
		(fp_poly
			(pts
				(xy 0.3048 -0.1016) (xy 0.3048 0.9906) (xy -0.3048 0.9906) (xy -0.3048 -0.1016)
			)
			(stroke
				(width 0)
				(type default)
			)
			(fill no)
			(layer "F.CrtYd")
		)
		(fp_line
			(start -0.3048 0.9906)
			(end 0.3048 0.9906)
			(stroke
				(width 0.1)
				(type default)
			)
			(layer "F.Fab")
		)
		(fp_line
			(start 0.3048 0.9906)
			(end 0.3048 -0.1016)
			(stroke
				(width 0.1)
				(type default)
			)
			(layer "F.Fab")
		)
		(fp_line
			(start -0.3048 -0.1016)
			(end -0.3048 0.9906)
			(stroke
				(width 0.1)
				(type default)
			)
			(layer "F.Fab")
		)
		(fp_line
			(start 0.3048 -0.1016)
			(end -0.3048 -0.1016)
			(stroke
				(width 0.1)
				(type default)
			)
			(layer "F.Fab")
		)
		(pad "1" smd rect
			(at 0 0 270)
			(size 0.508 0.508)
			(layers "F.Cu" "F.Mask" "F.Paste")
			(net "VR_PVDDQ_GHJ_AIINSEN")
		)
		(pad "2" smd rect
			(at 0 0.889 270)
			(size 0.508 0.508)
			(layers "F.Cu" "F.Mask" "F.Paste")
			(net "VR_PVDDQ_GHJ_VINSEN")
		)
		(zone
			(layer "F.Cu")
			(hatch none 0.5)
			(connect_pads
				(clearance 0)
			)
			(min_thickness 0.25)
			(keepout
				(tracks not_allowed)
				(vias allowed)
				(pads allowed)
				(copperpour not_allowed)
				(footprints allowed)
			)
			(placement
				(enabled no)
				(sheetname "")
			)
			(fill
				(thermal_gap 0.5)
				(thermal_bridge_width 0.5)
				(island_removal_mode 0)
			)
			(polygon
				(pts
					(xy 11.712702 3.844798) (xy 11.712702 4.352798) (xy 12.093702 4.352798) (xy 12.093702 3.844798)
				)
			)
		)
		(zone
			(layer "F.Cu")
			(hatch none 0.5)
			(connect_pads
				(clearance 0)
			)
			(min_thickness 0.25)
			(keepout
				(tracks allowed)
				(vias not_allowed)
				(pads allowed)
				(copperpour not_allowed)
				(footprints allowed)
			)
			(placement
				(enabled no)
				(sheetname "")
			)
			(fill
				(thermal_gap 0.5)
				(thermal_bridge_width 0.5)
				(island_removal_mode 0)
			)
			(polygon
				(pts
					(xy 12.093702 3.844798) (xy 12.093702 4.352798) (xy 11.712702 4.352798) (xy 11.712702 3.844798)
				)
			)
		)
	)
	(footprint ""
		(layer "F.Cu")
		(at 188.73978 -72.644 180)
		(property "Reference" "C4D29"
			(at 0 0 180)
			(layer "F.SilkS")
			(hide yes)
			(effects
				(font
					(size 1.27 1.27)
				)
			)
		)
		(property "Value" ""
			(at 0 0 180)
			(layer "F.Fab")
			(effects
				(font
					(size 1.27 1.27)
				)
			)
		)
		(duplicate_pad_numbers_are_jumpers no)
		(fp_rect
			(start 0.3048 -0.1016)
			(end -0.3048 0.9906)
			(stroke
				(width 0)
				(type default)
			)
			(fill no)
			(layer "F.CrtYd")
		)
		(fp_line
			(start 0.3048 0.9906)
			(end 0.3048 -0.1016)
			(stroke
				(width 0.1)
				(type default)
			)
			(layer "F.Fab")
		)
		(fp_line
			(start 0.3048 -0.1016)
			(end -0.3048 -0.1016)
			(stroke
				(width 0.1)
				(type default)
			)
			(layer "F.Fab")
		)
		(fp_line
			(start -0.3048 0.9906)
			(end 0.3048 0.9906)
			(stroke
				(width 0.1)
				(type default)
			)
			(layer "F.Fab")
		)
		(fp_line
			(start -0.3048 -0.1016)
			(end -0.3048 0.9906)
			(stroke
				(width 0.1)
				(type default)
			)
			(layer "F.Fab")
		)
		(pad "1" smd rect
			(at 0 0 180)
			(size 0.508 0.508)
			(layers "F.Cu" "F.Mask" "F.Paste")
			(net "VSENSE_PVSA_CPU0_BVSP")
		)
		(pad "2" smd rect
			(at 0 0.889 180)
			(size 0.508 0.508)
			(layers "F.Cu" "F.Mask" "F.Paste")
			(net "VSENSE_PVSA_CPU0_N")
		)
		(zone
			(layer "F.Cu")
			(hatch none 0.5)
			(connect_pads
				(clearance 0)
			)
			(min_thickness 0.25)
			(keepout
				(tracks allowed)
				(vias not_allowed)
				(pads allowed)
				(copperpour not_allowed)
				(footprints allowed)
			)
			(placement
				(enabled no)
				(sheetname "")
			)
			(fill
				(thermal_gap 0.5)
				(thermal_bridge_width 0.5)
				(island_removal_mode 0)
			)
			(polygon
				(pts
					(xy 188.48578 -72.898) (xy 188.99378 -72.898) (xy 188.99378 -73.279) (xy 188.48578 -73.279)
				)
			)
		)
		(zone
			(layer "F.Cu")
			(hatch none 0.5)
			(connect_pads
				(clearance 0)
			)
			(min_thickness 0.25)
			(keepout
				(tracks not_allowed)
				(vias allowed)
				(pads allowed)
				(copperpour not_allowed)
				(footprints allowed)
			)
			(placement
				(enabled no)
				(sheetname "")
			)
			(fill
				(thermal_gap 0.5)
				(thermal_bridge_width 0.5)
				(island_removal_mode 0)
			)
			(polygon
				(pts
					(xy 188.48578 -72.898) (xy 188.99378 -72.898) (xy 188.99378 -73.279) (xy 188.48578 -73.279)
				)
			)
		)
	)
	(footprint ""
		(layer "F.Cu")
		(at 171.99991 1.999996 90)
		(property "Reference" "TH4G1"
			(at 4.640326 3.13309 0)
			(unlocked yes)
			(layer "F.SilkS")
			(effects
				(font
					(size 0.7874 0.5842)
					(thickness 0.1524)
				)
				(justify left)
			)
		)
		(property "Value" ""
			(at 0 0 90)
			(layer "F.Fab")
			(effects
				(font
					(size 1.27 1.27)
				)
			)
		)
		(duplicate_pad_numbers_are_jumpers no)
		(fp_poly
			(pts
				(arc
					(start 3.0226 0.68834)
					(mid 3.042235 0.827855)
					(end 3.099562 0.956564)
				)
				(arc
					(start 3.099562 0.956564)
					(mid 4.012804 3.550073)
					(end 3.042158 6.12267)
				)
				(arc
					(start 3.042158 6.12267)
					(mid 0 7.518589)
					(end -3.042158 6.12267)
				)
				(arc
					(start -3.042158 6.12267)
					(mid -4.012854 3.55061)
					(end -3.100324 0.957326)
				)
				(arc
					(start -3.100324 0.957326)
					(mid -3.042498 0.827518)
					(end -3.0226 0.686816)
				)
				(arc
					(start -3.0226 -0.000254)
					(mid -2.137121 -2.137227)
					(end 0 -3.022346)
				)
				(arc
					(start 0 -3.022346)
					(mid 2.137227 -2.136973)
					(end 3.0226 0.000254)
				)
			)
			(stroke
				(width 0)
				(type default)
			)
			(fill no)
			(layer "F.CrtYd")
		)
		(pad "1" thru_hole custom
			(at 0 0 90)
			(size 2.00667 2.00667)
			(drill 0.3048)
			(layers "*.Cu" "*.Mask")
			(remove_unused_layers no)
			(net "GND")
			(clearance -0.889)
			(options
				(clearance outline)
				(anchor circle)
			)
			(primitives
				(gr_poly
					(pts
						(arc
							(start 3.042158 3.874516)
							(mid 0 5.270435)
							(end -3.042158 3.874516)
						)
						(arc
							(start -3.042158 3.874516)
							(mid -4.012854 1.302456)
							(end -3.100324 -1.290828)
						)
						(arc
							(start -3.100324 -1.290828)
							(mid -3.042498 -1.420636)
							(end -3.0226 -1.561338)
						)
						(arc
							(start -3.0226 -2.248408)
							(mid -2.137121 -4.385381)
							(end 0 -5.2705)
						)
						(arc
							(start 0 -5.2705)
							(mid 2.137227 -4.385127)
							(end 3.0226 -2.2479)
						)
						(arc
							(start 3.0226 -1.55956)
							(mid 3.04227 -1.420177)
							(end 3.099562 -1.29159)
						)
						(arc
							(start 3.099562 -1.29159)
							(mid 4.012804 1.301919)
							(end 3.042158 3.874516)
						)
					)
					(width 0)
					(fill yes)
				)
			)
		)
	)
)
